(kicad_pcb
	(version 20260206)
	(generator "pcbnew")
	(generator_version "10.0")
	(general
		(thickness 1.6)
		(legacy_teardrops no)
	)
	(paper "A4")
	(title_block
		(title "peb — Lightning_PEB_BRD.brd")
		(comment 1 "Lightning (Wiwynn / Facebook NVMe JBOF) / footprints 664-670 of 2563")
	)
	(layers
		(0 "F.Cu" signal "TOP")
		(4 "In1.Cu" signal "L2GND")
		(6 "In2.Cu" signal "L3")
		(8 "In3.Cu" signal "L4VCC")
		(10 "In4.Cu" signal "L5VCC")
		(12 "In5.Cu" signal "L6")
		(14 "In6.Cu" signal "L7GND")
		(2 "B.Cu" signal "BOTTOM")
		(9 "F.Adhes" user "F.Adhesive")
		(11 "B.Adhes" user "B.Adhesive")
		(13 "F.Paste" user "Package Geometry/Pastemask Top")
		(15 "B.Paste" user "Package Geometry/Pastemask Bottom")
		(5 "F.SilkS" user "Ref Des/Silkscreen Top")
		(7 "B.SilkS" user "Ref Des/Silkscreen Bottom")
		(1 "F.Mask" user "Board Geometry/Soldermask Top")
		(3 "B.Mask" user "Board Geometry/Soldermask Bottom")
		(17 "Dwgs.User" user "User.Drawings")
		(19 "Cmts.User" user "User.Comments")
		(21 "Eco1.User" user "User.Eco1")
		(23 "Eco2.User" user "User.Eco2")
		(25 "Edge.Cuts" user "Board Geometry/Outline")
		(27 "Margin" user)
		(31 "F.CrtYd" user "Package Geometry/Place Bound Top")
		(29 "B.CrtYd" user "Package Geometry/Place Bound Bottom")
		(35 "F.Fab" user "Ref Des/Assembly Top")
		(33 "B.Fab" user "Ref Des/Assembly Bottom")
	)
	(footprint ""
		(layer "F.Cu")
		(at 235.95838 -5.97916 90)
		(property "Reference" "R174"
			(at 0 0 90)
			(layer "F.SilkS")
			(hide yes)
			(effects
				(font
					(size 1.27 1.27)
				)
			)
		)
		(property "Value" "4K7R2F-GP"
			(at 0.064008 -3.993896 90)
			(unlocked yes)
			(layer "F.Fab")
			(hide yes)
			(effects
				(font
					(size 1.016 1.016)
					(thickness 0.1524)
				)
			)
		)
		(property "Device Type" "R402H16"
			(at 0.064008 -5.517896 90)
			(unlocked yes)
			(layer "F.Fab")
			(hide yes)
			(effects
				(font
					(size 1.016 1.016)
					(thickness 0.1524)
				)
			)
		)
		(duplicate_pad_numbers_are_jumpers no)
		(fp_line
			(start 0.508 -0.9398)
			(end -0.508 -0.9398)
			(stroke
				(width 0.1524)
				(type default)
			)
			(layer "F.SilkS")
		)
		(fp_line
			(start -0.508 -0.9398)
			(end -0.508 0.9398)
			(stroke
				(width 0.1524)
				(type default)
			)
			(layer "F.SilkS")
		)
		(fp_rect
			(start -0.508 0.9398)
			(end 0.508 -0.9398)
			(stroke
				(width 0)
				(type default)
			)
			(fill no)
			(layer "F.CrtYd")
		)
		(fp_rect
			(start -0.508 0.9398)
			(end 0.508 -0.9398)
			(stroke
				(width 0)
				(type default)
			)
			(fill no)
			(layer "F.Fab")
		)
		(pad "1" smd custom
			(at 0 -0.4445 90)
			(size 0.1397 0.1397)
			(layers "F.Cu" "F.Mask" "F.Paste")
			(net "P3V3_STBY")
			(options
				(clearance outline)
				(anchor circle)
			)
			(primitives
				(gr_poly
					(pts
						(arc
							(start -0.1778 -0.2794)
							(mid -0.249642 -0.249642)
							(end -0.2794 -0.1778)
						)
						(arc
							(start -0.2794 0.1778)
							(mid -0.249642 0.249642)
							(end -0.1778 0.2794)
						)
						(arc
							(start 0.1778 0.2794)
							(mid 0.249642 0.249642)
							(end 0.2794 0.1778)
						)
						(arc
							(start 0.2794 -0.1778)
							(mid 0.249642 -0.249642)
							(end 0.1778 -0.2794)
						)
					)
					(width 0)
					(fill yes)
				)
			)
		)
		(pad "2" smd custom
			(at 0 0.4445 90)
			(size 0.1397 0.1397)
			(layers "F.Cu" "F.Mask" "F.Paste")
			(net "DP_RST_N")
			(options
				(clearance outline)
				(anchor circle)
			)
			(primitives
				(gr_poly
					(pts
						(arc
							(start -0.1778 -0.2794)
							(mid -0.249642 -0.249642)
							(end -0.2794 -0.1778)
						)
						(arc
							(start -0.2794 0.1778)
							(mid -0.249642 0.249642)
							(end -0.1778 0.2794)
						)
						(arc
							(start 0.1778 0.2794)
							(mid 0.249642 0.249642)
							(end 0.2794 0.1778)
						)
						(arc
							(start 0.2794 -0.1778)
							(mid 0.249642 -0.249642)
							(end 0.1778 -0.2794)
						)
					)
					(width 0)
					(fill yes)
				)
			)
		)
	)
	(footprint ""
		(layer "F.Cu")
		(at 145.177002 -76.430632 -90)
		(property "Reference" "PC214"
			(at 0 0 270)
			(layer "F.SilkS")
			(hide yes)
			(effects
				(font
					(size 1.27 1.27)
				)
			)
		)
		(property "Value" "SC22U25V6KX-GP-U"
			(at -2.860802 -5.279644 270)
			(unlocked yes)
			(layer "F.Fab")
			(hide yes)
			(effects
				(font
					(size 1.016 1.016)
					(thickness 0.1524)
				)
			)
		)
		(property "Device Type" "C1206-TO0D3H75"
			(at -2.860802 -6.803644 270)
			(unlocked yes)
			(layer "F.Fab")
			(hide yes)
			(effects
				(font
					(size 1.016 1.016)
					(thickness 0.1524)
				)
			)
		)
		(duplicate_pad_numbers_are_jumpers no)
		(fp_line
			(start -1.3081 2.3749)
			(end -1.3081 -2.3749)
			(stroke
				(width 0.1524)
				(type default)
			)
			(layer "F.SilkS")
		)
		(fp_line
			(start 1.3081 2.3749)
			(end -1.3081 2.3749)
			(stroke
				(width 0.1524)
				(type default)
			)
			(layer "F.SilkS")
		)
		(fp_line
			(start -1.3081 -2.3749)
			(end 1.3081 -2.3749)
			(stroke
				(width 0.1524)
				(type default)
			)
			(layer "F.SilkS")
		)
		(fp_line
			(start 1.3081 -2.3749)
			(end 1.3081 2.3749)
			(stroke
				(width 0.1524)
				(type default)
			)
			(layer "F.SilkS")
		)
		(fp_rect
			(start -0.8001 1.6002)
			(end 0.8001 -1.6002)
			(stroke
				(width 0)
				(type default)
			)
			(fill no)
			(layer "F.CrtYd")
		)
		(fp_poly
			(pts
				(xy -1.5621 2.4511) (xy -1.5621 1.6002) (xy 0.8001 1.6002) (xy 0.8001 -1.6002) (xy -0.8001 -1.6002)
				(xy -0.8001 1.5875) (xy -1.5621 1.5875) (xy -1.5621 -2.4511) (xy 1.5621 -2.4511) (xy 1.5621 2.4511)
			)
			(stroke
				(width 0)
				(type default)
			)
			(fill no)
			(layer "F.CrtYd")
		)
		(fp_rect
			(start -1.5621 2.4511)
			(end 1.5621 -2.4511)
			(stroke
				(width 0)
				(type default)
			)
			(fill no)
			(layer "F.Fab")
		)
		(pad "1" smd rect
			(at 0 -1.392936 270)
			(size 2.1082 1.4478)
			(layers "F.Cu" "F.Mask" "F.Paste")
			(net "P0V9_VIN")
		)
		(pad "2" smd rect
			(at 0 1.392936 270)
			(size 2.1082 1.4478)
			(layers "F.Cu" "F.Mask" "F.Paste")
			(net "GND")
		)
	)
	(footprint ""
		(layer "F.Cu")
		(at 40.9956 -77.5716 180)
		(property "Reference" "PC68"
			(at 0 0 180)
			(layer "F.SilkS")
			(hide yes)
			(effects
				(font
					(size 1.27 1.27)
				)
			)
		)
		(property "Value" "SC22U16V5MX-4-GP"
			(at -0.0762 -6.1214 180)
			(unlocked yes)
			(layer "F.Fab")
			(hide yes)
			(effects
				(font
					(size 1.016 1.016)
					(thickness 0.1524)
				)
			)
		)
		(property "Device Type" "C805H58"
			(at -0.0762 -8.1534 180)
			(unlocked yes)
			(layer "F.Fab")
			(hide yes)
			(effects
				(font
					(size 1.016 1.016)
					(thickness 0.1524)
				)
			)
		)
		(duplicate_pad_numbers_are_jumpers no)
		(fp_line
			(start 0.635 0)
			(end -0.635 0)
			(stroke
				(width 0.508)
				(type default)
			)
			(layer "F.SilkS")
		)
		(fp_rect
			(start -0.9652 1.778)
			(end 0.9652 -1.778)
			(stroke
				(width 0)
				(type default)
			)
			(fill no)
			(layer "F.CrtYd")
		)
		(fp_poly
			(pts
				(xy -0.9652 -1.778) (xy 0.9652 -1.778) (xy 0.9652 1.778) (xy -0.9652 1.778)
			)
			(stroke
				(width 0)
				(type default)
			)
			(fill no)
			(layer "F.Fab")
		)
		(pad "1" smd rect
			(at 0 -0.9652 180)
			(size 1.397 1.143)
			(layers "F.Cu" "F.Mask" "F.Paste")
			(net "P5V_STBY_LR")
		)
		(pad "2" smd rect
			(at 0 0.9652 180)
			(size 1.397 1.143)
			(layers "F.Cu" "F.Mask" "F.Paste")
			(net "GND")
		)
	)
	(footprint ""
		(layer "F.Cu")
		(at 188.6458 -3.3782)
		(property "Reference" "R943"
			(at 0 0 0)
			(layer "F.SilkS")
			(hide yes)
			(effects
				(font
					(size 1.27 1.27)
				)
			)
		)
		(property "Value" "4K7R2F-GP"
			(at 0.064008 -3.993896 0)
			(unlocked yes)
			(layer "F.Fab")
			(hide yes)
			(effects
				(font
					(size 1.016 1.016)
					(thickness 0.1524)
				)
			)
		)
		(property "Device Type" "R402H16"
			(at 0.064008 -5.517896 0)
			(unlocked yes)
			(layer "F.Fab")
			(hide yes)
			(effects
				(font
					(size 1.016 1.016)
					(thickness 0.1524)
				)
			)
		)
		(duplicate_pad_numbers_are_jumpers no)
		(fp_line
			(start -0.508 -0.9398)
			(end -0.508 0.9398)
			(stroke
				(width 0.1524)
				(type default)
			)
			(layer "F.SilkS")
		)
		(fp_line
			(start 0.508 -0.9398)
			(end -0.508 -0.9398)
			(stroke
				(width 0.1524)
				(type default)
			)
			(layer "F.SilkS")
		)
		(fp_rect
			(start -0.508 0.9398)
			(end 0.508 -0.9398)
			(stroke
				(width 0)
				(type default)
			)
			(fill no)
			(layer "F.CrtYd")
		)
		(fp_rect
			(start -0.508 0.9398)
			(end 0.508 -0.9398)
			(stroke
				(width 0)
				(type default)
			)
			(fill no)
			(layer "F.Fab")
		)
		(pad "1" smd custom
			(at 0 -0.4445)
			(size 0.1397 0.1397)
			(layers "F.Cu" "F.Mask" "F.Paste")
			(net "P3V3_STBY")
			(options
				(clearance outline)
				(anchor circle)
			)
			(primitives
				(gr_poly
					(pts
						(arc
							(start -0.1778 -0.2794)
							(mid -0.249642 -0.249642)
							(end -0.2794 -0.1778)
						)
						(arc
							(start -0.2794 0.1778)
							(mid -0.249642 0.249642)
							(end -0.1778 0.2794)
						)
						(arc
							(start 0.1778 0.2794)
							(mid 0.249642 0.249642)
							(end 0.2794 0.1778)
						)
						(arc
							(start 0.2794 -0.1778)
							(mid 0.249642 -0.249642)
							(end 0.1778 -0.2794)
						)
					)
					(width 0)
					(fill yes)
				)
			)
		)
		(pad "2" smd custom
			(at 0 0.4445)
			(size 0.1397 0.1397)
			(layers "F.Cu" "F.Mask" "F.Paste")
			(net "WP_DISABLE")
			(options
				(clearance outline)
				(anchor circle)
			)
			(primitives
				(gr_poly
					(pts
						(arc
							(start -0.1778 -0.2794)
							(mid -0.249642 -0.249642)
							(end -0.2794 -0.1778)
						)
						(arc
							(start -0.2794 0.1778)
							(mid -0.249642 0.249642)
							(end -0.1778 0.2794)
						)
						(arc
							(start 0.1778 0.2794)
							(mid 0.249642 0.249642)
							(end 0.2794 0.1778)
						)
						(arc
							(start 0.2794 -0.1778)
							(mid 0.249642 -0.249642)
							(end 0.1778 -0.2794)
						)
					)
					(width 0)
					(fill yes)
				)
			)
		)
	)
	(footprint ""
		(layer "F.Cu")
		(at 255.524762 -6.097778 180)
		(property "Reference" "U4"
			(at 0 0 180)
			(layer "F.SilkS")
			(hide yes)
			(effects
				(font
					(size 1.27 1.27)
				)
			)
		)
		(property "Value" "MAX6654MEE-2-GP"
			(at -0.127 -12.4968 180)
			(unlocked yes)
			(layer "F.Fab")
			(hide yes)
			(effects
				(font
					(size 1.016 1.016)
					(thickness 0.1524)
				)
			)
		)
		(property "Device Type" "QSOIC16H69"
			(at -0.2032 -14.1478 180)
			(unlocked yes)
			(layer "F.Fab")
			(hide yes)
			(effects
				(font
					(size 1.016 1.016)
					(thickness 0.1524)
				)
			)
		)
		(duplicate_pad_numbers_are_jumpers no)
		(fp_line
			(start 2.3114 1.5748)
			(end 2.3114 -1.5748)
			(stroke
				(width 0.1524)
				(type default)
			)
			(layer "F.SilkS")
		)
		(fp_line
			(start 2.3114 1.5748)
			(end -2.794 1.5748)
			(stroke
				(width 0.1524)
				(type default)
			)
			(layer "F.SilkS")
		)
		(fp_line
			(start 2.3114 -1.5748)
			(end -2.7178 -1.5748)
			(stroke
				(width 0.1524)
				(type default)
			)
			(layer "F.SilkS")
		)
		(fp_line
			(start -2.4638 0)
			(end -2.7178 0.254)
			(stroke
				(width 0.1524)
				(type default)
			)
			(layer "F.SilkS")
		)
		(fp_line
			(start -2.7178 1.5748)
			(end -2.7178 -1.5748)
			(stroke
				(width 0.1524)
				(type default)
			)
			(layer "F.SilkS")
		)
		(fp_line
			(start -2.7178 -0.254)
			(end -2.4638 0)
			(stroke
				(width 0.1524)
				(type default)
			)
			(layer "F.SilkS")
		)
		(fp_line
			(start -2.794 1.5748)
			(end -2.794 3.302)
			(stroke
				(width 0.508)
				(type default)
			)
			(layer "F.SilkS")
		)
		(fp_poly
			(pts
				(xy -2.3876 -1.5748) (xy 2.3114 -1.5748) (xy 2.3114 1.5748) (xy -2.3876 1.5748)
			)
			(stroke
				(width 0)
				(type default)
			)
			(fill yes)
			(layer "F.SilkS")
		)
		(fp_rect
			(start -2.794 3.556)
			(end 2.794 -3.556)
			(stroke
				(width 0)
				(type default)
			)
			(fill no)
			(layer "F.CrtYd")
		)
		(fp_poly
			(pts
				(xy -2.794 -3.556) (xy 2.794 -3.556) (xy 2.794 3.556) (xy -2.794 3.556)
			)
			(stroke
				(width 0)
				(type default)
			)
			(fill no)
			(layer "F.Fab")
		)
		(pad "1" smd rect
			(at -2.2225 2.6162 180)
			(size 0.3556 1.524)
			(layers "F.Cu" "F.Mask" "F.Paste")
			(net "Net_2088")
		)
		(pad "2" smd rect
			(at -1.5875 2.6162 180)
			(size 0.3556 1.524)
			(layers "F.Cu" "F.Mask" "F.Paste")
			(net "P3V3_STBY")
		)
		(pad "3" smd rect
			(at -0.9525 2.6162 180)
			(size 0.3556 1.524)
			(layers "F.Cu" "F.Mask" "F.Paste")
			(net "THERM_EMIT_R")
		)
		(pad "4" smd rect
			(at -0.3175 2.6162 180)
			(size 0.3556 1.524)
			(layers "F.Cu" "F.Mask" "F.Paste")
			(net "THERM_BASE_R")
		)
		(pad "5" smd rect
			(at 0.3175 2.6162 180)
			(size 0.3556 1.524)
			(layers "F.Cu" "F.Mask" "F.Paste")
			(net "Net_2087")
		)
		(pad "6" smd rect
			(at 0.9525 2.6162 180)
			(size 0.3556 1.524)
			(layers "F.Cu" "F.Mask" "F.Paste")
			(net "MAX6654_ADD1")
		)
		(pad "7" smd rect
			(at 1.5875 2.6162 180)
			(size 0.3556 1.524)
			(layers "F.Cu" "F.Mask" "F.Paste")
			(net "GND")
		)
		(pad "8" smd rect
			(at 2.2225 2.6162 180)
			(size 0.3556 1.524)
			(layers "F.Cu" "F.Mask" "F.Paste")
			(net "GND")
		)
		(pad "9" smd rect
			(at 2.2225 -2.6162 180)
			(size 0.3556 1.524)
			(layers "F.Cu" "F.Mask" "F.Paste")
			(net "Net_2086")
		)
		(pad "10" smd rect
			(at 1.5875 -2.6162 180)
			(size 0.3556 1.524)
			(layers "F.Cu" "F.Mask" "F.Paste")
			(net "MAX6654_ADD0")
		)
		(pad "11" smd rect
			(at 0.9525 -2.6162 180)
			(size 0.3556 1.524)
			(layers "F.Cu" "F.Mask" "F.Paste")
			(net "MAX6654_ALERT#")
		)
		(pad "12" smd rect
			(at 0.3175 -2.6162 180)
			(size 0.3556 1.524)
			(layers "F.Cu" "F.Mask" "F.Paste")
			(net "I2C_MAX6654_DAT")
		)
		(pad "13" smd rect
			(at -0.3175 -2.6162 180)
			(size 0.3556 1.524)
			(layers "F.Cu" "F.Mask" "F.Paste")
			(net "Net_2085")
		)
		(pad "14" smd rect
			(at -0.9525 -2.6162 180)
			(size 0.3556 1.524)
			(layers "F.Cu" "F.Mask" "F.Paste")
			(net "I2C_MAX6654_CLK")
		)
		(pad "15" smd rect
			(at -1.5875 -2.6162 180)
			(size 0.3556 1.524)
			(layers "F.Cu" "F.Mask" "F.Paste")
			(net "P3V3_STBY")
		)
		(pad "16" smd rect
			(at -2.2225 -2.6162 180)
			(size 0.3556 1.524)
			(layers "F.Cu" "F.Mask" "F.Paste")
			(net "Net_2084")
		)
	)
	(footprint ""
		(layer "F.Cu")
		(at 71.501 -34.417 180)
		(property "Reference" "PR18"
			(at 0 0 180)
			(layer "F.SilkS")
			(hide yes)
			(effects
				(font
					(size 1.27 1.27)
				)
			)
		)
		(property "Value" "1K4R2F-1-GP"
			(at 0.064008 -3.993896 180)
			(unlocked yes)
			(layer "F.Fab")
			(hide yes)
			(effects
				(font
					(size 1.016 1.016)
					(thickness 0.1524)
				)
			)
		)
		(property "Device Type" "R402H16"
			(at 0.064008 -5.517896 180)
			(unlocked yes)
			(layer "F.Fab")
			(hide yes)
			(effects
				(font
					(size 1.016 1.016)
					(thickness 0.1524)
				)
			)
		)
		(duplicate_pad_numbers_are_jumpers no)
		(fp_line
			(start 0.508 -0.9398)
			(end -0.508 -0.9398)
			(stroke
				(width 0.1524)
				(type default)
			)
			(layer "F.SilkS")
		)
		(fp_line
			(start -0.508 -0.9398)
			(end -0.508 0.9398)
			(stroke
				(width 0.1524)
				(type default)
			)
			(layer "F.SilkS")
		)
		(fp_rect
			(start -0.508 0.9398)
			(end 0.508 -0.9398)
			(stroke
				(width 0)
				(type default)
			)
			(fill no)
			(layer "F.CrtYd")
		)
		(fp_rect
			(start -0.508 0.9398)
			(end 0.508 -0.9398)
			(stroke
				(width 0)
				(type default)
			)
			(fill no)
			(layer "F.Fab")
		)
		(pad "1" smd custom
			(at 0 -0.4445 180)
			(size 0.1397 0.1397)
			(layers "F.Cu" "F.Mask" "F.Paste")
			(net "P5V_STBY")
			(options
				(clearance outline)
				(anchor circle)
			)
			(primitives
				(gr_poly
					(pts
						(arc
							(start -0.1778 -0.2794)
							(mid -0.249642 -0.249642)
							(end -0.2794 -0.1778)
						)
						(arc
							(start -0.2794 0.1778)
							(mid -0.249642 0.249642)
							(end -0.1778 0.2794)
						)
						(arc
							(start 0.1778 0.2794)
							(mid 0.249642 0.249642)
							(end 0.2794 0.1778)
						)
						(arc
							(start 0.2794 -0.1778)
							(mid 0.249642 -0.249642)
							(end 0.1778 -0.2794)
						)
					)
					(width 0)
					(fill yes)
				)
			)
		)
		(pad "2" smd custom
			(at 0 0.4445 180)
			(size 0.1397 0.1397)
			(layers "F.Cu" "F.Mask" "F.Paste")
			(net "P3V3_STBY_EN")
			(options
				(clearance outline)
				(anchor circle)
			)
			(primitives
				(gr_poly
					(pts
						(arc
							(start -0.1778 -0.2794)
							(mid -0.249642 -0.249642)
							(end -0.2794 -0.1778)
						)
						(arc
							(start -0.2794 0.1778)
							(mid -0.249642 0.249642)
							(end -0.1778 0.2794)
						)
						(arc
							(start 0.1778 0.2794)
							(mid 0.249642 0.249642)
							(end 0.2794 0.1778)
						)
						(arc
							(start 0.2794 -0.1778)
							(mid 0.249642 -0.249642)
							(end 0.1778 -0.2794)
						)
					)
					(width 0)
					(fill yes)
				)
			)
		)
	)
	(footprint ""
		(layer "F.Cu")
		(at 229.108 -91.059 -90)
		(property "Reference" "R592"
			(at 0 0 270)
			(layer "F.SilkS")
			(hide yes)
			(effects
				(font
					(size 1.27 1.27)
				)
			)
		)
		(property "Value" "4K7R2F-GP"
			(at 0.064008 -3.993896 270)
			(unlocked yes)
			(layer "F.Fab")
			(hide yes)
			(effects
				(font
					(size 1.016 1.016)
					(thickness 0.1524)
				)
			)
		)
		(property "Device Type" "R402H16"
			(at 0.064008 -5.517896 270)
			(unlocked yes)
			(layer "F.Fab")
			(hide yes)
			(effects
				(font
					(size 1.016 1.016)
					(thickness 0.1524)
				)
			)
		)
		(duplicate_pad_numbers_are_jumpers no)
		(fp_line
			(start -0.508 -0.9398)
			(end -0.508 0.9398)
			(stroke
				(width 0.1524)
				(type default)
			)
			(layer "F.SilkS")
		)
		(fp_line
			(start 0.508 -0.9398)
			(end -0.508 -0.9398)
			(stroke
				(width 0.1524)
				(type default)
			)
			(layer "F.SilkS")
		)
		(fp_rect
			(start -0.508 0.9398)
			(end 0.508 -0.9398)
			(stroke
				(width 0)
				(type default)
			)
			(fill no)
			(layer "F.CrtYd")
		)
		(fp_rect
			(start -0.508 0.9398)
			(end 0.508 -0.9398)
			(stroke
				(width 0)
				(type default)
			)
			(fill no)
			(layer "F.Fab")
		)
		(pad "1" smd custom
			(at 0 -0.4445 270)
			(size 0.1397 0.1397)
			(layers "F.Cu" "F.Mask" "F.Paste")
			(net "P3V3_STBY")
			(options
				(clearance outline)
				(anchor circle)
			)
			(primitives
				(gr_poly
					(pts
						(arc
							(start -0.1778 -0.2794)
							(mid -0.249642 -0.249642)
							(end -0.2794 -0.1778)
						)
						(arc
							(start -0.2794 0.1778)
							(mid -0.249642 0.249642)
							(end -0.1778 0.2794)
						)
						(arc
							(start 0.1778 0.2794)
							(mid 0.249642 0.249642)
							(end 0.2794 0.1778)
						)
						(arc
							(start 0.2794 -0.1778)
							(mid 0.249642 -0.249642)
							(end 0.1778 -0.2794)
						)
					)
					(width 0)
					(fill yes)
				)
			)
		)
		(pad "2" smd custom
			(at 0 0.4445 270)
			(size 0.1397 0.1397)
			(layers "F.Cu" "F.Mask" "F.Paste")
			(net "TEMP_3_A0")
			(options
				(clearance outline)
				(anchor circle)
			)
			(primitives
				(gr_poly
					(pts
						(arc
							(start -0.1778 -0.2794)
							(mid -0.249642 -0.249642)
							(end -0.2794 -0.1778)
						)
						(arc
							(start -0.2794 0.1778)
							(mid -0.249642 0.249642)
							(end -0.1778 0.2794)
						)
						(arc
							(start 0.1778 0.2794)
							(mid 0.249642 0.249642)
							(end 0.2794 0.1778)
						)
						(arc
							(start 0.2794 -0.1778)
							(mid 0.249642 -0.249642)
							(end 0.1778 -0.2794)
						)
					)
					(width 0)
					(fill yes)
				)
			)
		)
	)
)
